(kicad_pcb
	(version 20260206)
	(generator "pcbnew")
	(generator_version "10.0")
	(general
		(thickness 1.6)
		(legacy_teardrops no)
	)
	(paper "A4")
	(title_block
		(title "04192023_DAF0TMB3IC0_F0TG_MB_C_brd_V02_OCP.brd")
		(comment 1 "Grand Teton / footprints 2359-2360 of 8354")
	)
	(layers
		(0 "F.Cu" signal "TOP")
		(4 "In1.Cu" signal "GND")
		(6 "In2.Cu" signal "IN1")
		(8 "In3.Cu" signal "GND1")
		(10 "In4.Cu" signal "IN2")
		(12 "In5.Cu" signal "GND2")
		(14 "In6.Cu" signal "IN3")
		(16 "In7.Cu" signal "GND3")
		(18 "In8.Cu" signal "VCC")
		(20 "In9.Cu" signal "VCC1")
		(22 "In10.Cu" signal "GND4")
		(24 "In11.Cu" signal "IN4")
		(26 "In12.Cu" signal "GND5")
		(28 "In13.Cu" signal "IN5")
		(30 "In14.Cu" signal "GND6")
		(32 "In15.Cu" signal "IN6")
		(34 "In16.Cu" signal "GND7")
		(2 "B.Cu" signal "BOTTOM")
		(9 "F.Adhes" user "F.Adhesive")
		(11 "B.Adhes" user "B.Adhesive")
		(13 "F.Paste" user "Package Geometry/Pastemask Top")
		(15 "B.Paste" user "Package Geometry/Pastemask Bottom")
		(5 "F.SilkS" user "Ref Des/Silkscreen Top")
		(7 "B.SilkS" user "Ref Des/Silkscreen Bottom")
		(1 "F.Mask" user "Board Geometry/Soldermask Top")
		(3 "B.Mask" user "Board Geometry/Soldermask Bottom")
		(17 "Dwgs.User" user "User.Drawings")
		(19 "Cmts.User" user "User.Comments")
		(21 "Eco1.User" user "User.Eco1")
		(23 "Eco2.User" user "User.Eco2")
		(25 "Edge.Cuts" user "Board Geometry/Outline")
		(27 "Margin" user)
		(31 "F.CrtYd" user "Package Geometry/Place Bound Top")
		(29 "B.CrtYd" user "Package Geometry/Place Bound Bottom")
		(35 "F.Fab" user "Ref Des/Assembly Top")
		(33 "B.Fab" user "Ref Des/Assembly Bottom")
	)
	(footprint ""
		(layer "F.Cu")
		(at 362.025438 -408.915616 180)
		(property "Reference" "R9015"
			(at 0 0 180)
			(layer "F.SilkS")
			(hide yes)
			(effects
				(font
					(size 1.27 1.27)
				)
			)
		)
		(property "Value" ""
			(at 0 0 180)
			(layer "F.Fab")
			(effects
				(font
					(size 1.27 1.27)
				)
			)
		)
		(duplicate_pad_numbers_are_jumpers no)
		(fp_line
			(start 0.7874 0.4064)
			(end -0.7874 0.4064)
			(stroke
				(width 0.1524)
				(type default)
			)
			(layer "F.SilkS")
		)
		(fp_line
			(start 0.7874 -0.4064)
			(end 0.7874 0.4064)
			(stroke
				(width 0.1524)
				(type default)
			)
			(layer "F.SilkS")
		)
		(fp_line
			(start -0.7874 0.4064)
			(end -0.7874 -0.4064)
			(stroke
				(width 0.1524)
				(type default)
			)
			(layer "F.SilkS")
		)
		(fp_line
			(start -0.7874 -0.4064)
			(end 0.7874 -0.4064)
			(stroke
				(width 0.1524)
				(type default)
			)
			(layer "F.SilkS")
		)
		(fp_line
			(start 0.67945 0.3048)
			(end 0.120396 0.3048)
			(stroke
				(width 0.1)
				(type default)
			)
			(layer "F.Fab")
		)
		(fp_line
			(start 0.67945 -0.3048)
			(end 0.67945 0.3048)
			(stroke
				(width 0.1)
				(type default)
			)
			(layer "F.Fab")
		)
		(fp_line
			(start 0.12065 -0.2794)
			(end 0.12065 -0.3048)
			(stroke
				(width 0.1)
				(type default)
			)
			(layer "F.Fab")
		)
		(fp_line
			(start 0.12065 -0.3048)
			(end 0.67945 -0.3048)
			(stroke
				(width 0.1)
				(type default)
			)
			(layer "F.Fab")
		)
		(fp_line
			(start 0.120396 0.3048)
			(end 0.120396 0.2794)
			(stroke
				(width 0.1)
				(type default)
			)
			(layer "F.Fab")
		)
		(fp_line
			(start 0.120396 0.2794)
			(end -0.12065 0.2794)
			(stroke
				(width 0.1)
				(type default)
			)
			(layer "F.Fab")
		)
		(fp_line
			(start -0.12065 0.3048)
			(end -0.67945 0.3048)
			(stroke
				(width 0.1)
				(type default)
			)
			(layer "F.Fab")
		)
		(fp_line
			(start -0.12065 0.2794)
			(end -0.12065 0.3048)
			(stroke
				(width 0.1)
				(type default)
			)
			(layer "F.Fab")
		)
		(fp_line
			(start -0.12065 -0.2794)
			(end 0.12065 -0.2794)
			(stroke
				(width 0.1)
				(type default)
			)
			(layer "F.Fab")
		)
		(fp_line
			(start -0.12065 -0.305054)
			(end -0.12065 -0.2794)
			(stroke
				(width 0.1)
				(type default)
			)
			(layer "F.Fab")
		)
		(fp_line
			(start -0.67945 0.3048)
			(end -0.67945 -0.305054)
			(stroke
				(width 0.1)
				(type default)
			)
			(layer "F.Fab")
		)
		(fp_line
			(start -0.67945 -0.305054)
			(end -0.12065 -0.305054)
			(stroke
				(width 0.1)
				(type default)
			)
			(layer "F.Fab")
		)
		(pad "1" smd circle
			(at -0.40005 0 180)
			(size 0 0)
			(layers "F.Cu" "F.Mask" "F.Paste")
			(net "PRSNT_CABLE_GPU_A3_N")
		)
		(pad "2" smd circle
			(at 0.40005 0 180)
			(size 0 0)
			(layers "F.Cu" "F.Mask" "F.Paste")
			(net "GND")
		)
	)
	(footprint ""
		(layer "F.Cu")
		(at 299.772578 -13.41501 180)
		(property "Reference" "R4188"
			(at 0 0 180)
			(layer "F.SilkS")
			(hide yes)
			(effects
				(font
					(size 1.27 1.27)
				)
			)
		)
		(property "Value" ""
			(at 0 0 180)
			(layer "F.Fab")
			(effects
				(font
					(size 1.27 1.27)
				)
			)
		)
		(duplicate_pad_numbers_are_jumpers no)
		(fp_line
			(start 0.7874 0.4064)
			(end -0.7874 0.4064)
			(stroke
				(width 0.1524)
				(type default)
			)
			(layer "F.SilkS")
		)
		(fp_line
			(start 0.7874 -0.4064)
			(end 0.7874 0.4064)
			(stroke
				(width 0.1524)
				(type default)
			)
			(layer "F.SilkS")
		)
		(fp_line
			(start -0.7874 0.4064)
			(end -0.7874 -0.4064)
			(stroke
				(width 0.1524)
				(type default)
			)
			(layer "F.SilkS")
		)
		(fp_line
			(start -0.7874 -0.4064)
			(end 0.7874 -0.4064)
			(stroke
				(width 0.1524)
				(type default)
			)
			(layer "F.SilkS")
		)
		(fp_line
			(start 0.67945 0.3048)
			(end 0.120396 0.3048)
			(stroke
				(width 0.1)
				(type default)
			)
			(layer "F.Fab")
		)
		(fp_line
			(start 0.67945 -0.3048)
			(end 0.67945 0.3048)
			(stroke
				(width 0.1)
				(type default)
			)
			(layer "F.Fab")
		)
		(fp_line
			(start 0.12065 -0.2794)
			(end 0.12065 -0.3048)
			(stroke
				(width 0.1)
				(type default)
			)
			(layer "F.Fab")
		)
		(fp_line
			(start 0.12065 -0.3048)
			(end 0.67945 -0.3048)
			(stroke
				(width 0.1)
				(type default)
			)
			(layer "F.Fab")
		)
		(fp_line
			(start 0.120396 0.3048)
			(end 0.120396 0.2794)
			(stroke
				(width 0.1)
				(type default)
			)
			(layer "F.Fab")
		)
		(fp_line
			(start 0.120396 0.2794)
			(end -0.12065 0.2794)
			(stroke
				(width 0.1)
				(type default)
			)
			(layer "F.Fab")
		)
		(fp_line
			(start -0.12065 0.3048)
			(end -0.67945 0.3048)
			(stroke
				(width 0.1)
				(type default)
			)
			(layer "F.Fab")
		)
		(fp_line
			(start -0.12065 0.2794)
			(end -0.12065 0.3048)
			(stroke
				(width 0.1)
				(type default)
			)
			(layer "F.Fab")
		)
		(fp_line
			(start -0.12065 -0.2794)
			(end 0.12065 -0.2794)
			(stroke
				(width 0.1)
				(type default)
			)
			(layer "F.Fab")
		)
		(fp_line
			(start -0.12065 -0.305054)
			(end -0.12065 -0.2794)
			(stroke
				(width 0.1)
				(type default)
			)
			(layer "F.Fab")
		)
		(fp_line
			(start -0.67945 0.3048)
			(end -0.67945 -0.305054)
			(stroke
				(width 0.1)
				(type default)
			)
			(layer "F.Fab")
		)
		(fp_line
			(start -0.67945 -0.305054)
			(end -0.12065 -0.305054)
			(stroke
				(width 0.1)
				(type default)
			)
			(layer "F.Fab")
		)
		(pad "1" smd circle
			(at -0.40005 0 180)
			(size 0 0)
			(layers "F.Cu" "F.Mask" "F.Paste")
			(net "P3V3_AUX")
		)
		(pad "2" smd circle
			(at 0.40005 0 180)
			(size 0 0)
			(layers "F.Cu" "F.Mask" "F.Paste")
			(net "U271_1_ADD2")
		)
	)
)
